(kicad_pcb
	(version 20260206)
	(generator "pcbnew")
	(generator_version "10.0")
	(general
		(thickness 1.6)
		(legacy_teardrops no)
	)
	(paper "A4")
	(title_block
		(title "04192023_DAF0TMB3IC0_F0TG_MB_C_brd_V02_OCP.brd")
		(comment 1 "Grand Teton / footprints 7295-7301 of 8354")
	)
	(layers
		(0 "F.Cu" signal "TOP")
		(4 "In1.Cu" signal "GND")
		(6 "In2.Cu" signal "IN1")
		(8 "In3.Cu" signal "GND1")
		(10 "In4.Cu" signal "IN2")
		(12 "In5.Cu" signal "GND2")
		(14 "In6.Cu" signal "IN3")
		(16 "In7.Cu" signal "GND3")
		(18 "In8.Cu" signal "VCC")
		(20 "In9.Cu" signal "VCC1")
		(22 "In10.Cu" signal "GND4")
		(24 "In11.Cu" signal "IN4")
		(26 "In12.Cu" signal "GND5")
		(28 "In13.Cu" signal "IN5")
		(30 "In14.Cu" signal "GND6")
		(32 "In15.Cu" signal "IN6")
		(34 "In16.Cu" signal "GND7")
		(2 "B.Cu" signal "BOTTOM")
		(9 "F.Adhes" user "F.Adhesive")
		(11 "B.Adhes" user "B.Adhesive")
		(13 "F.Paste" user "Package Geometry/Pastemask Top")
		(15 "B.Paste" user "Package Geometry/Pastemask Bottom")
		(5 "F.SilkS" user "Ref Des/Silkscreen Top")
		(7 "B.SilkS" user "Ref Des/Silkscreen Bottom")
		(1 "F.Mask" user "Board Geometry/Soldermask Top")
		(3 "B.Mask" user "Board Geometry/Soldermask Bottom")
		(17 "Dwgs.User" user "User.Drawings")
		(19 "Cmts.User" user "User.Comments")
		(21 "Eco1.User" user "User.Eco1")
		(23 "Eco2.User" user "User.Eco2")
		(25 "Edge.Cuts" user "Board Geometry/Outline")
		(27 "Margin" user)
		(31 "F.CrtYd" user "Package Geometry/Place Bound Top")
		(29 "B.CrtYd" user "Package Geometry/Place Bound Bottom")
		(35 "F.Fab" user "Ref Des/Assembly Top")
		(33 "B.Fab" user "Ref Des/Assembly Bottom")
	)
	(footprint ""
		(layer "B.Cu")
		(at 299.265594 -395.10716 180)
		(property "Reference" "R981"
			(at 0 0 0)
			(layer "B.SilkS")
			(hide yes)
			(effects
				(font
					(size 1.27 1.27)
				)
				(justify mirror)
			)
		)
		(property "Value" ""
			(at 0 0 0)
			(layer "B.Fab")
			(effects
				(font
					(size 1.27 1.27)
				)
				(justify mirror)
			)
		)
		(duplicate_pad_numbers_are_jumpers no)
		(fp_line
			(start 0.32512 0.175006)
			(end 0.32512 -0.175006)
			(stroke
				(width 0.1)
				(type default)
			)
			(layer "B.Fab")
		)
		(fp_line
			(start 0.32512 -0.175006)
			(end -0.32512 -0.175006)
			(stroke
				(width 0.1)
				(type default)
			)
			(layer "B.Fab")
		)
		(fp_line
			(start -0.32512 0.175006)
			(end 0.32512 0.175006)
			(stroke
				(width 0.1)
				(type default)
			)
			(layer "B.Fab")
		)
		(fp_line
			(start -0.32512 -0.175006)
			(end -0.32512 0.175006)
			(stroke
				(width 0.1)
				(type default)
			)
			(layer "B.Fab")
		)
		(pad "1" smd rect
			(at 0.2667 0)
			(size 0.3048 0.381)
			(layers "B.Cu" "B.Mask" "B.Paste")
			(net "P1V8_CPU0_RT_1D")
		)
		(pad "2" smd rect
			(at -0.2667 0 180)
			(size 0.3048 0.381)
			(layers "B.Cu" "B.Mask" "B.Paste")
			(net "TEST0_RT_CPU0_P0")
		)
	)
	(footprint ""
		(layer "B.Cu")
		(at 369.392454 -264.35431)
		(property "Reference" "C2630"
			(at 0 0 0)
			(layer "B.SilkS")
			(hide yes)
			(effects
				(font
					(size 1.27 1.27)
				)
				(justify mirror)
			)
		)
		(property "Value" ""
			(at 0 0 0)
			(layer "B.Fab")
			(effects
				(font
					(size 1.27 1.27)
				)
				(justify mirror)
			)
		)
		(duplicate_pad_numbers_are_jumpers no)
		(fp_line
			(start -0.7874 -0.4064)
			(end -0.7874 0.4064)
			(stroke
				(width 0.1524)
				(type default)
			)
			(layer "B.SilkS")
		)
		(fp_line
			(start -0.7874 0.4064)
			(end 0.7874 0.4064)
			(stroke
				(width 0.1524)
				(type default)
			)
			(layer "B.SilkS")
		)
		(fp_line
			(start 0.7874 -0.4064)
			(end -0.7874 -0.4064)
			(stroke
				(width 0.1524)
				(type default)
			)
			(layer "B.SilkS")
		)
		(fp_line
			(start 0.7874 0.4064)
			(end 0.7874 -0.4064)
			(stroke
				(width 0.1524)
				(type default)
			)
			(layer "B.SilkS")
		)
		(fp_line
			(start -0.67945 -0.3048)
			(end -0.67945 0.3048)
			(stroke
				(width 0.1)
				(type default)
			)
			(layer "B.Fab")
		)
		(fp_line
			(start -0.67945 0.3048)
			(end -0.120396 0.3048)
			(stroke
				(width 0.1)
				(type default)
			)
			(layer "B.Fab")
		)
		(fp_line
			(start -0.12065 -0.3048)
			(end -0.67945 -0.3048)
			(stroke
				(width 0.1)
				(type default)
			)
			(layer "B.Fab")
		)
		(fp_line
			(start -0.12065 -0.2794)
			(end -0.12065 -0.3048)
			(stroke
				(width 0.1)
				(type default)
			)
			(layer "B.Fab")
		)
		(fp_line
			(start -0.120396 0.2794)
			(end 0.12065 0.2794)
			(stroke
				(width 0.1)
				(type default)
			)
			(layer "B.Fab")
		)
		(fp_line
			(start -0.120396 0.3048)
			(end -0.120396 0.2794)
			(stroke
				(width 0.1)
				(type default)
			)
			(layer "B.Fab")
		)
		(fp_line
			(start 0.12065 -0.305054)
			(end 0.12065 -0.2794)
			(stroke
				(width 0.1)
				(type default)
			)
			(layer "B.Fab")
		)
		(fp_line
			(start 0.12065 -0.2794)
			(end -0.12065 -0.2794)
			(stroke
				(width 0.1)
				(type default)
			)
			(layer "B.Fab")
		)
		(fp_line
			(start 0.12065 0.2794)
			(end 0.12065 0.3048)
			(stroke
				(width 0.1)
				(type default)
			)
			(layer "B.Fab")
		)
		(fp_line
			(start 0.12065 0.3048)
			(end 0.67945 0.3048)
			(stroke
				(width 0.1)
				(type default)
			)
			(layer "B.Fab")
		)
		(fp_line
			(start 0.67945 -0.305054)
			(end 0.12065 -0.305054)
			(stroke
				(width 0.1)
				(type default)
			)
			(layer "B.Fab")
		)
		(fp_line
			(start 0.67945 0.3048)
			(end 0.67945 -0.305054)
			(stroke
				(width 0.1)
				(type default)
			)
			(layer "B.Fab")
		)
		(pad "1" smd circle
			(at 0.40005 0 180)
			(size 0 0)
			(layers "B.Cu" "B.Mask" "B.Paste")
			(net "PVDD11_S3_P0")
		)
		(pad "2" smd circle
			(at -0.40005 0 180)
			(size 0 0)
			(layers "B.Cu" "B.Mask" "B.Paste")
			(net "GND")
		)
	)
	(footprint ""
		(layer "B.Cu")
		(at 36.040568 -194.9196 180)
		(property "Reference" "R1583"
			(at 0 0 0)
			(layer "B.SilkS")
			(hide yes)
			(effects
				(font
					(size 1.27 1.27)
				)
				(justify mirror)
			)
		)
		(property "Value" ""
			(at 0 0 0)
			(layer "B.Fab")
			(effects
				(font
					(size 1.27 1.27)
				)
				(justify mirror)
			)
		)
		(duplicate_pad_numbers_are_jumpers no)
		(fp_line
			(start 0.7874 0.4064)
			(end 0.7874 -0.4064)
			(stroke
				(width 0.1524)
				(type default)
			)
			(layer "B.SilkS")
		)
		(fp_line
			(start 0.7874 -0.4064)
			(end -0.7874 -0.4064)
			(stroke
				(width 0.1524)
				(type default)
			)
			(layer "B.SilkS")
		)
		(fp_line
			(start -0.7874 0.4064)
			(end 0.7874 0.4064)
			(stroke
				(width 0.1524)
				(type default)
			)
			(layer "B.SilkS")
		)
		(fp_line
			(start -0.7874 -0.4064)
			(end -0.7874 0.4064)
			(stroke
				(width 0.1524)
				(type default)
			)
			(layer "B.SilkS")
		)
		(fp_line
			(start 0.67945 0.3048)
			(end 0.67945 -0.305054)
			(stroke
				(width 0.1)
				(type default)
			)
			(layer "B.Fab")
		)
		(fp_line
			(start 0.67945 -0.305054)
			(end 0.12065 -0.305054)
			(stroke
				(width 0.1)
				(type default)
			)
			(layer "B.Fab")
		)
		(fp_line
			(start 0.12065 0.3048)
			(end 0.67945 0.3048)
			(stroke
				(width 0.1)
				(type default)
			)
			(layer "B.Fab")
		)
		(fp_line
			(start 0.12065 0.2794)
			(end 0.12065 0.3048)
			(stroke
				(width 0.1)
				(type default)
			)
			(layer "B.Fab")
		)
		(fp_line
			(start 0.12065 -0.2794)
			(end -0.12065 -0.2794)
			(stroke
				(width 0.1)
				(type default)
			)
			(layer "B.Fab")
		)
		(fp_line
			(start 0.12065 -0.305054)
			(end 0.12065 -0.2794)
			(stroke
				(width 0.1)
				(type default)
			)
			(layer "B.Fab")
		)
		(fp_line
			(start -0.120396 0.3048)
			(end -0.120396 0.2794)
			(stroke
				(width 0.1)
				(type default)
			)
			(layer "B.Fab")
		)
		(fp_line
			(start -0.120396 0.2794)
			(end 0.12065 0.2794)
			(stroke
				(width 0.1)
				(type default)
			)
			(layer "B.Fab")
		)
		(fp_line
			(start -0.12065 -0.2794)
			(end -0.12065 -0.3048)
			(stroke
				(width 0.1)
				(type default)
			)
			(layer "B.Fab")
		)
		(fp_line
			(start -0.12065 -0.3048)
			(end -0.67945 -0.3048)
			(stroke
				(width 0.1)
				(type default)
			)
			(layer "B.Fab")
		)
		(fp_line
			(start -0.67945 0.3048)
			(end -0.120396 0.3048)
			(stroke
				(width 0.1)
				(type default)
			)
			(layer "B.Fab")
		)
		(fp_line
			(start -0.67945 -0.3048)
			(end -0.67945 0.3048)
			(stroke
				(width 0.1)
				(type default)
			)
			(layer "B.Fab")
		)
		(pad "1" smd circle
			(at 0.40005 0)
			(size 0 0)
			(layers "B.Cu" "B.Mask" "B.Paste")
			(net "I3C_SPD_DDRAF_CPU1_SCL")
		)
		(pad "2" smd circle
			(at -0.40005 0)
			(size 0 0)
			(layers "B.Cu" "B.Mask" "B.Paste")
			(net "I3C_SPD_DDRD_CPU1_SCL")
		)
	)
	(footprint ""
		(layer "B.Cu")
		(at 175.133 -126.238 180)
		(property "Reference" "R6852"
			(at 0 0 0)
			(layer "B.SilkS")
			(hide yes)
			(effects
				(font
					(size 1.27 1.27)
				)
				(justify mirror)
			)
		)
		(property "Value" ""
			(at 0 0 0)
			(layer "B.Fab")
			(effects
				(font
					(size 1.27 1.27)
				)
				(justify mirror)
			)
		)
		(duplicate_pad_numbers_are_jumpers no)
		(fp_line
			(start 0.7874 0.4064)
			(end 0.7874 -0.4064)
			(stroke
				(width 0.1524)
				(type default)
			)
			(layer "B.SilkS")
		)
		(fp_line
			(start 0.7874 -0.4064)
			(end -0.7874 -0.4064)
			(stroke
				(width 0.1524)
				(type default)
			)
			(layer "B.SilkS")
		)
		(fp_line
			(start -0.7874 0.4064)
			(end 0.7874 0.4064)
			(stroke
				(width 0.1524)
				(type default)
			)
			(layer "B.SilkS")
		)
		(fp_line
			(start -0.7874 -0.4064)
			(end -0.7874 0.4064)
			(stroke
				(width 0.1524)
				(type default)
			)
			(layer "B.SilkS")
		)
		(fp_line
			(start 0.67945 0.3048)
			(end 0.67945 -0.305054)
			(stroke
				(width 0.1)
				(type default)
			)
			(layer "B.Fab")
		)
		(fp_line
			(start 0.67945 -0.305054)
			(end 0.12065 -0.305054)
			(stroke
				(width 0.1)
				(type default)
			)
			(layer "B.Fab")
		)
		(fp_line
			(start 0.12065 0.3048)
			(end 0.67945 0.3048)
			(stroke
				(width 0.1)
				(type default)
			)
			(layer "B.Fab")
		)
		(fp_line
			(start 0.12065 0.2794)
			(end 0.12065 0.3048)
			(stroke
				(width 0.1)
				(type default)
			)
			(layer "B.Fab")
		)
		(fp_line
			(start 0.12065 -0.2794)
			(end -0.12065 -0.2794)
			(stroke
				(width 0.1)
				(type default)
			)
			(layer "B.Fab")
		)
		(fp_line
			(start 0.12065 -0.305054)
			(end 0.12065 -0.2794)
			(stroke
				(width 0.1)
				(type default)
			)
			(layer "B.Fab")
		)
		(fp_line
			(start -0.120396 0.3048)
			(end -0.120396 0.2794)
			(stroke
				(width 0.1)
				(type default)
			)
			(layer "B.Fab")
		)
		(fp_line
			(start -0.120396 0.2794)
			(end 0.12065 0.2794)
			(stroke
				(width 0.1)
				(type default)
			)
			(layer "B.Fab")
		)
		(fp_line
			(start -0.12065 -0.2794)
			(end -0.12065 -0.3048)
			(stroke
				(width 0.1)
				(type default)
			)
			(layer "B.Fab")
		)
		(fp_line
			(start -0.12065 -0.3048)
			(end -0.67945 -0.3048)
			(stroke
				(width 0.1)
				(type default)
			)
			(layer "B.Fab")
		)
		(fp_line
			(start -0.67945 0.3048)
			(end -0.120396 0.3048)
			(stroke
				(width 0.1)
				(type default)
			)
			(layer "B.Fab")
		)
		(fp_line
			(start -0.67945 -0.3048)
			(end -0.67945 0.3048)
			(stroke
				(width 0.1)
				(type default)
			)
			(layer "B.Fab")
		)
		(pad "1" smd circle
			(at 0.40005 0)
			(size 0 0)
			(layers "B.Cu" "B.Mask" "B.Paste")
			(net "PWRGD_P0V9_RETIMER_CPU0")
		)
		(pad "2" smd circle
			(at -0.40005 0)
			(size 0 0)
			(layers "B.Cu" "B.Mask" "B.Paste")
			(net "PWRGD_P0V9_RETIMER_CPU0_R2")
		)
	)
	(footprint ""
		(layer "B.Cu")
		(at 14.407388 -111.004604 90)
		(property "Reference" "C5229"
			(at 0 0 90)
			(layer "B.SilkS")
			(hide yes)
			(effects
				(font
					(size 1.27 1.27)
				)
				(justify mirror)
			)
		)
		(property "Value" ""
			(at 0 0 90)
			(layer "B.Fab")
			(effects
				(font
					(size 1.27 1.27)
				)
				(justify mirror)
			)
		)
		(duplicate_pad_numbers_are_jumpers no)
		(fp_line
			(start 0.7874 -0.4064)
			(end -0.7874 -0.4064)
			(stroke
				(width 0.1524)
				(type default)
			)
			(layer "B.SilkS")
		)
		(fp_line
			(start -0.7874 -0.4064)
			(end -0.7874 0.4064)
			(stroke
				(width 0.1524)
				(type default)
			)
			(layer "B.SilkS")
		)
		(fp_line
			(start 0.7874 0.4064)
			(end 0.7874 -0.4064)
			(stroke
				(width 0.1524)
				(type default)
			)
			(layer "B.SilkS")
		)
		(fp_line
			(start -0.7874 0.4064)
			(end 0.7874 0.4064)
			(stroke
				(width 0.1524)
				(type default)
			)
			(layer "B.SilkS")
		)
		(fp_line
			(start 0.67945 -0.305054)
			(end 0.12065 -0.305054)
			(stroke
				(width 0.1)
				(type default)
			)
			(layer "B.Fab")
		)
		(fp_line
			(start 0.12065 -0.305054)
			(end 0.12065 -0.2794)
			(stroke
				(width 0.1)
				(type default)
			)
			(layer "B.Fab")
		)
		(fp_line
			(start -0.12065 -0.3048)
			(end -0.67945 -0.3048)
			(stroke
				(width 0.1)
				(type default)
			)
			(layer "B.Fab")
		)
		(fp_line
			(start -0.67945 -0.3048)
			(end -0.67945 0.3048)
			(stroke
				(width 0.1)
				(type default)
			)
			(layer "B.Fab")
		)
		(fp_line
			(start 0.12065 -0.2794)
			(end -0.12065 -0.2794)
			(stroke
				(width 0.1)
				(type default)
			)
			(layer "B.Fab")
		)
		(fp_line
			(start -0.12065 -0.2794)
			(end -0.12065 -0.3048)
			(stroke
				(width 0.1)
				(type default)
			)
			(layer "B.Fab")
		)
		(fp_line
			(start 0.12065 0.2794)
			(end 0.12065 0.3048)
			(stroke
				(width 0.1)
				(type default)
			)
			(layer "B.Fab")
		)
		(fp_line
			(start -0.120396 0.2794)
			(end 0.12065 0.2794)
			(stroke
				(width 0.1)
				(type default)
			)
			(layer "B.Fab")
		)
		(fp_line
			(start 0.67945 0.3048)
			(end 0.67945 -0.305054)
			(stroke
				(width 0.1)
				(type default)
			)
			(layer "B.Fab")
		)
		(fp_line
			(start 0.12065 0.3048)
			(end 0.67945 0.3048)
			(stroke
				(width 0.1)
				(type default)
			)
			(layer "B.Fab")
		)
		(fp_line
			(start -0.120396 0.3048)
			(end -0.120396 0.2794)
			(stroke
				(width 0.1)
				(type default)
			)
			(layer "B.Fab")
		)
		(fp_line
			(start -0.67945 0.3048)
			(end -0.120396 0.3048)
			(stroke
				(width 0.1)
				(type default)
			)
			(layer "B.Fab")
		)
		(pad "1" smd circle
			(at 0.40005 0 270)
			(size 0 0)
			(layers "B.Cu" "B.Mask" "B.Paste")
			(net "P3V3_AUX")
		)
		(pad "2" smd circle
			(at -0.40005 0 270)
			(size 0 0)
			(layers "B.Cu" "B.Mask" "B.Paste")
			(net "GND")
		)
	)
	(footprint ""
		(layer "B.Cu")
		(at 180.0352 -106.71048 90)
		(property "Reference" "C352"
			(at 0 0 90)
			(layer "B.SilkS")
			(hide yes)
			(effects
				(font
					(size 1.27 1.27)
				)
				(justify mirror)
			)
		)
		(property "Value" ""
			(at 0 0 90)
			(layer "B.Fab")
			(effects
				(font
					(size 1.27 1.27)
				)
				(justify mirror)
			)
		)
		(duplicate_pad_numbers_are_jumpers no)
		(fp_line
			(start 0.7874 -0.4064)
			(end -0.7874 -0.4064)
			(stroke
				(width 0.1524)
				(type default)
			)
			(layer "B.SilkS")
		)
		(fp_line
			(start -0.7874 -0.4064)
			(end -0.7874 0.4064)
			(stroke
				(width 0.1524)
				(type default)
			)
			(layer "B.SilkS")
		)
		(fp_line
			(start 0.7874 0.4064)
			(end 0.7874 -0.4064)
			(stroke
				(width 0.1524)
				(type default)
			)
			(layer "B.SilkS")
		)
		(fp_line
			(start -0.7874 0.4064)
			(end 0.7874 0.4064)
			(stroke
				(width 0.1524)
				(type default)
			)
			(layer "B.SilkS")
		)
		(fp_line
			(start 0.67945 -0.305054)
			(end 0.12065 -0.305054)
			(stroke
				(width 0.1)
				(type default)
			)
			(layer "B.Fab")
		)
		(fp_line
			(start 0.12065 -0.305054)
			(end 0.12065 -0.2794)
			(stroke
				(width 0.1)
				(type default)
			)
			(layer "B.Fab")
		)
		(fp_line
			(start -0.12065 -0.3048)
			(end -0.67945 -0.3048)
			(stroke
				(width 0.1)
				(type default)
			)
			(layer "B.Fab")
		)
		(fp_line
			(start -0.67945 -0.3048)
			(end -0.67945 0.3048)
			(stroke
				(width 0.1)
				(type default)
			)
			(layer "B.Fab")
		)
		(fp_line
			(start 0.12065 -0.2794)
			(end -0.12065 -0.2794)
			(stroke
				(width 0.1)
				(type default)
			)
			(layer "B.Fab")
		)
		(fp_line
			(start -0.12065 -0.2794)
			(end -0.12065 -0.3048)
			(stroke
				(width 0.1)
				(type default)
			)
			(layer "B.Fab")
		)
		(fp_line
			(start 0.12065 0.2794)
			(end 0.12065 0.3048)
			(stroke
				(width 0.1)
				(type default)
			)
			(layer "B.Fab")
		)
		(fp_line
			(start -0.120396 0.2794)
			(end 0.12065 0.2794)
			(stroke
				(width 0.1)
				(type default)
			)
			(layer "B.Fab")
		)
		(fp_line
			(start 0.67945 0.3048)
			(end 0.67945 -0.305054)
			(stroke
				(width 0.1)
				(type default)
			)
			(layer "B.Fab")
		)
		(fp_line
			(start 0.12065 0.3048)
			(end 0.67945 0.3048)
			(stroke
				(width 0.1)
				(type default)
			)
			(layer "B.Fab")
		)
		(fp_line
			(start -0.120396 0.3048)
			(end -0.120396 0.2794)
			(stroke
				(width 0.1)
				(type default)
			)
			(layer "B.Fab")
		)
		(fp_line
			(start -0.67945 0.3048)
			(end -0.120396 0.3048)
			(stroke
				(width 0.1)
				(type default)
			)
			(layer "B.Fab")
		)
		(pad "1" smd circle
			(at 0.40005 0 270)
			(size 0 0)
			(layers "B.Cu" "B.Mask" "B.Paste")
			(net "P1V8_AUX")
		)
		(pad "2" smd circle
			(at -0.40005 0 270)
			(size 0 0)
			(layers "B.Cu" "B.Mask" "B.Paste")
			(net "GND")
		)
	)
	(footprint ""
		(layer "B.Cu")
		(at 18.01749 -400.953732)
		(property "Reference" "PC6819"
			(at 0 0 0)
			(layer "B.SilkS")
			(hide yes)
			(effects
				(font
					(size 1.27 1.27)
				)
				(justify mirror)
			)
		)
		(property "Value" ""
			(at 0 0 0)
			(layer "B.Fab")
			(effects
				(font
					(size 1.27 1.27)
				)
				(justify mirror)
			)
		)
		(duplicate_pad_numbers_are_jumpers no)
		(fp_line
			(start -1.524 -0.762)
			(end -1.524 0.762)
			(stroke
				(width 0.1524)
				(type default)
			)
			(layer "B.SilkS")
		)
		(fp_line
			(start -1.524 0.762)
			(end 1.524 0.762)
			(stroke
				(width 0.1524)
				(type default)
			)
			(layer "B.SilkS")
		)
		(fp_line
			(start 1.524 -0.762)
			(end -1.524 -0.762)
			(stroke
				(width 0.1524)
				(type default)
			)
			(layer "B.SilkS")
		)
		(fp_line
			(start 1.524 0.762)
			(end 1.524 -0.762)
			(stroke
				(width 0.1524)
				(type default)
			)
			(layer "B.SilkS")
		)
		(fp_line
			(start -1.1049 -0.724916)
			(end 1.1049 -0.724916)
			(stroke
				(width 0.1)
				(type default)
			)
			(layer "B.Fab")
		)
		(fp_line
			(start -1.1049 0.724916)
			(end -1.1049 -0.724916)
			(stroke
				(width 0.1)
				(type default)
			)
			(layer "B.Fab")
		)
		(fp_line
			(start 1.1049 -0.724916)
			(end 1.1049 0.724916)
			(stroke
				(width 0.1)
				(type default)
			)
			(layer "B.Fab")
		)
		(fp_line
			(start 1.1049 0.724916)
			(end -1.1049 0.724916)
			(stroke
				(width 0.1)
				(type default)
			)
			(layer "B.Fab")
		)
		(pad "1" smd rect
			(at 0.889 0)
			(size 1.016 1.27)
			(layers "B.Cu" "B.Mask" "B.Paste")
			(net "SW_P12V_AUX_P0V9_RETIMER_CPU1_FLT")
		)
		(pad "2" smd rect
			(at -0.889 0)
			(size 1.016 1.27)
			(layers "B.Cu" "B.Mask" "B.Paste")
			(net "GND")
		)
	)
)
